# TIMECARD (Time Appliance Project (Time Card)) — schematic netlist excerpt (pin names and nets, part order shuffled) for the footprints in the layout excerpt that follows; sources: Cadence DE-HDL packaged netlist, KiCad conversion of R4006-B0001-02_R01.brd

C183  CAPACITOR  0.1UF 25V 10% X7R  pkg SMC_0402R_H022  page 30 : \1\ = XP3R3V ; \2\ = SG
R222  RESISTOR  100OHM 1%  pkg SMC_0402R_H016  page 10 : \1\ = FPGA_M2 ; \2\ = SG

(kicad_pcb
	(version 20260206)
	(generator "pcbnew")
	(generator_version "10.0")
	(general
		(thickness 1.6)
		(legacy_teardrops no)
	)
	(paper "A4")
	(title_block
		(title "timecard-production-celestica-r4006 — R4006-B0001-02_R01.brd")
		(comment 1 "Time Appliance Project (Time Card) / footprints 134-135 of 1113")
	)
	(layers
		(0 "F.Cu" signal "TOP")
		(4 "In1.Cu" signal "L02_GND1")
		(6 "In2.Cu" signal "L03_SIG1")
		(8 "In3.Cu" signal "L04_GND2")
		(10 "In4.Cu" signal "L05_VCC1")
		(12 "In5.Cu" signal "L06_VCC2")
		(14 "In6.Cu" signal "L07_GND3")
		(16 "In7.Cu" signal "L08_SIG2")
		(18 "In8.Cu" signal "L09_GND4")
		(2 "B.Cu" signal "BOTTOM")
		(9 "F.Adhes" user "F.Adhesive")
		(11 "B.Adhes" user "B.Adhesive")
		(13 "F.Paste" user "Package Geometry/Pastemask Top")
		(15 "B.Paste" user "Package Geometry/Pastemask Bottom")
		(5 "F.SilkS" user "Ref Des/Silkscreen Top")
		(7 "B.SilkS" user "Ref Des/Silkscreen Bottom")
		(1 "F.Mask" user "Board Geometry/Soldermask Top")
		(3 "B.Mask" user "Board Geometry/Soldermask Bottom")
		(17 "Dwgs.User" user "User.Drawings")
		(19 "Cmts.User" user "User.Comments")
		(21 "Eco1.User" user "User.Eco1")
		(23 "Eco2.User" user "User.Eco2")
		(25 "Edge.Cuts" user "Board Geometry/Outline")
		(27 "Margin" user)
		(31 "F.CrtYd" user "Package Geometry/Place Bound Top")
		(29 "B.CrtYd" user "Package Geometry/Place Bound Bottom")
		(35 "F.Fab" user "Ref Des/Assembly Top")
		(33 "B.Fab" user "Ref Des/Assembly Bottom")
	)
	(footprint ""
		(layer "F.Cu")
		(at 126.492 -36.322)
		(property "Reference" "R222"
			(at 2.921 1.56337 0)
			(unlocked yes)
			(layer "F.SilkS")
			(effects
				(font
					(size 0.7874 0.5842)
					(thickness 0.1524)
				)
			)
		)
		(property "Value" "VAL*"
			(at 0.02032 2.13233 0)
			(unlocked yes)
			(layer "F.Fab")
			(hide yes)
			(effects
				(font
					(size 0.7874 0.5842)
					(thickness 0.1524)
				)
			)
		)
		(property "Device Type" "RESISTOR-G155-11000-01,100OHM,A"
			(at 0.008382 1.210564 0)
			(unlocked yes)
			(layer "F.Fab")
			(hide yes)
			(effects
				(font
					(size 0.7874 0.5842)
					(thickness 0.1524)
				)
			)
		)
		(property "User Part Number" "PARTNUM*"
			(at 0.02032 4.024884 0)
			(unlocked yes)
			(layer "Cmts.User")
			(hide yes)
			(effects
				(font
					(size 0.7874 0.5842)
					(thickness 0.1524)
				)
			)
		)
		(property "Tolerance" "TOL*"
			(at 0.044704 3.05435 0)
			(unlocked yes)
			(layer "Cmts.User")
			(hide yes)
			(effects
				(font
					(size 0.7874 0.5842)
					(thickness 0.1524)
				)
			)
		)
		(duplicate_pad_numbers_are_jumpers no)
		(fp_line
			(start -1.143 -0.5588)
			(end -1.143 0.5588)
			(stroke
				(width 0.1)
				(type default)
			)
			(layer "F.SilkS")
		)
		(fp_line
			(start -1.143 0.5588)
			(end 1.143 0.5588)
			(stroke
				(width 0.1)
				(type default)
			)
			(layer "F.SilkS")
		)
		(fp_line
			(start 1.143 -0.5588)
			(end -1.143 -0.5588)
			(stroke
				(width 0.1)
				(type default)
			)
			(layer "F.SilkS")
		)
		(fp_line
			(start 1.143 0.5588)
			(end 1.143 -0.5588)
			(stroke
				(width 0.1)
				(type default)
			)
			(layer "F.SilkS")
		)
		(fp_rect
			(start -1.143 0.5588)
			(end 1.143 -0.5588)
			(stroke
				(width 0)
				(type default)
			)
			(fill no)
			(layer "F.CrtYd")
		)
		(fp_line
			(start -0.508 -0.3048)
			(end -0.508 0.3048)
			(stroke
				(width 0.1)
				(type default)
			)
			(layer "F.Fab")
		)
		(fp_line
			(start -0.508 0.3048)
			(end 0.508 0.3048)
			(stroke
				(width 0.1)
				(type default)
			)
			(layer "F.Fab")
		)
		(fp_line
			(start 0.508 -0.3048)
			(end -0.508 -0.3048)
			(stroke
				(width 0.1)
				(type default)
			)
			(layer "F.Fab")
		)
		(fp_line
			(start 0.508 0.3048)
			(end 0.508 -0.3048)
			(stroke
				(width 0.1)
				(type default)
			)
			(layer "F.Fab")
		)
		(pad "1" smd rect
			(at -0.5334 0)
			(size 0.7112 0.6096)
			(layers "F.Cu" "F.Mask" "F.Paste")
			(net "FPGA_M2")
		)
		(pad "2" smd rect
			(at 0.5334 0)
			(size 0.7112 0.6096)
			(layers "F.Cu" "F.Mask" "F.Paste")
			(net "SG")
		)
		(zone
			(layer "F.Cu")
			(hatch none 0.5)
			(connect_pads
				(clearance 0)
			)
			(min_thickness 0.25)
			(keepout
				(tracks allowed)
				(vias not_allowed)
				(pads allowed)
				(copperpour not_allowed)
				(footprints allowed)
			)
			(placement
				(enabled no)
				(sheetname "")
			)
			(fill
				(thermal_gap 0.5)
				(thermal_bridge_width 0.5)
				(island_removal_mode 0)
			)
			(polygon
				(pts
					(xy 126.4158 -36.0172) (xy 126.5682 -36.0172) (xy 126.5682 -36.6268) (xy 126.4158 -36.6268)
				)
			)
		)
	)
	(footprint ""
		(layer "F.Cu")
		(at 127.889 -62.8396)
		(property "Reference" "C183"
			(at 1.143 4.83997 0)
			(unlocked yes)
			(layer "F.SilkS")
			(effects
				(font
					(size 0.7874 0.5842)
					(thickness 0.1524)
				)
			)
		)
		(property "Value" "VAL*"
			(at 0.0762 2.067306 0)
			(unlocked yes)
			(layer "F.Fab")
			(hide yes)
			(effects
				(font
					(size 0.7874 0.5842)
					(thickness 0.1524)
				)
			)
		)
		(property "Device Type" "CAPACITOR-G105-0B104-EK,0.1UF,A"
			(at 0.0508 1.127506 0)
			(unlocked yes)
			(layer "F.Fab")
			(hide yes)
			(effects
				(font
					(size 0.7874 0.5842)
					(thickness 0.1524)
				)
			)
		)
		(property "User Part Number" "PARTNUM*"
			(at 0.1016 4.023106 0)
			(unlocked yes)
			(layer "Cmts.User")
			(hide yes)
			(effects
				(font
					(size 0.7874 0.5842)
					(thickness 0.1524)
				)
			)
		)
		(property "Tolerance" "TOL*"
			(at 0.0762 3.032506 0)
			(unlocked yes)
			(layer "Cmts.User")
			(hide yes)
			(effects
				(font
					(size 0.7874 0.5842)
					(thickness 0.1524)
				)
			)
		)
		(duplicate_pad_numbers_are_jumpers no)
		(fp_line
			(start -1.143 -0.5588)
			(end -1.143 0.5588)
			(stroke
				(width 0.1)
				(type default)
			)
			(layer "F.SilkS")
		)
		(fp_line
			(start -1.143 0.5588)
			(end 1.143 0.5588)
			(stroke
				(width 0.1)
				(type default)
			)
			(layer "F.SilkS")
		)
		(fp_line
			(start 1.143 -0.5588)
			(end -1.143 -0.5588)
			(stroke
				(width 0.1)
				(type default)
			)
			(layer "F.SilkS")
		)
		(fp_line
			(start 1.143 0.5588)
			(end 1.143 -0.5588)
			(stroke
				(width 0.1)
				(type default)
			)
			(layer "F.SilkS")
		)
		(fp_rect
			(start 1.143 -0.5588)
			(end -1.143 0.5588)
			(stroke
				(width 0)
				(type default)
			)
			(fill no)
			(layer "F.CrtYd")
		)
		(fp_line
			(start -0.508 -0.3048)
			(end -0.508 0.3048)
			(stroke
				(width 0.1)
				(type default)
			)
			(layer "F.Fab")
		)
		(fp_line
			(start -0.508 0.3048)
			(end 0.508 0.3048)
			(stroke
				(width 0.1)
				(type default)
			)
			(layer "F.Fab")
		)
		(fp_line
			(start 0.508 -0.3048)
			(end -0.508 -0.3048)
			(stroke
				(width 0.1)
				(type default)
			)
			(layer "F.Fab")
		)
		(fp_line
			(start 0.508 0.3048)
			(end 0.508 -0.3048)
			(stroke
				(width 0.1)
				(type default)
			)
			(layer "F.Fab")
		)
		(pad "1" smd rect
			(at -0.5334 0)
			(size 0.7112 0.6096)
			(layers "F.Cu" "F.Mask" "F.Paste")
			(net "XP3R3V")
		)
		(pad "2" smd rect
			(at 0.5334 0)
			(size 0.7112 0.6096)
			(layers "F.Cu" "F.Mask" "F.Paste")
			(net "SG")
		)
		(zone
			(layer "F.Cu")
			(hatch none 0.5)
			(connect_pads
				(clearance 0)
			)
			(min_thickness 0.25)
			(keepout
				(tracks allowed)
				(vias not_allowed)
				(pads allowed)
				(copperpour not_allowed)
				(footprints allowed)
			)
			(placement
				(enabled no)
				(sheetname "")
			)
			(fill
				(thermal_gap 0.5)
				(thermal_bridge_width 0.5)
				(island_removal_mode 0)
			)
			(polygon
				(pts
					(xy 127.9652 -63.1444) (xy 127.8128 -63.1444) (xy 127.8128 -62.5348) (xy 127.9652 -62.5348)
				)
			)
		)
	)
)
